# OCuLink to 10GbE adapter — KiCad project settings (.kicad_pro: net classes, design rules, text variables)
{
  "board": {
    "3dviewports": [],
    "design_settings": {
      "defaults": {
        "apply_defaults_to_fp_fields": false,
        "apply_defaults_to_fp_shapes": false,
        "apply_defaults_to_fp_text": false,
        "board_outline_line_width": 0.1,
        "copper_line_width": 0.2,
        "copper_text_italic": false,
        "copper_text_size_h": 1.5,
        "copper_text_size_v": 1.5,
        "copper_text_thickness": 0.3,
        "copper_text_upright": false,
        "courtyard_line_width": 0.05,
        "dimension_precision": 4,
        "dimension_units": 3,
        "dimensions": {
          "arrow_length": 1270000,
          "extension_offset": 500000,
          "keep_text_aligned": true,
          "suppress_zeroes": true,
          "text_position": 0,
          "units_format": 0
        },
        "fab_line_width": 0.1,
        "fab_text_italic": false,
        "fab_text_size_h": 1.0,
        "fab_text_size_v": 1.0,
        "fab_text_thickness": 0.15,
        "fab_text_upright": false,
        "other_line_width": 0.15,
        "other_text_italic": false,
        "other_text_size_h": 1.0,
        "other_text_size_v": 1.0,
        "other_text_thickness": 0.15,
        "other_text_upright": false,
        "pads": {
          "drill": 3.2,
          "height": 6.0,
          "width": 6.0
        },
        "silk_line_width": 0.15,
        "silk_text_italic": false,
        "silk_text_size_h": 1.0,
        "silk_text_size_v": 1.0,
        "silk_text_thickness": 0.15,
        "silk_text_upright": false,
        "zones": {
          "min_clearance": 0.2
        }
      },
      "diff_pair_dimensions": [
        {
          "gap": 0.0,
          "via_gap": 0.0,
          "width": 0.0
        }
      ],
      "drc_exclusions": [],
      "meta": {
        "version": 2
      },
      "rule_severities": {
        "annular_width": "error",
        "clearance": "error",
        "connection_width": "warning",
        "copper_edge_clearance": "error",
        "copper_sliver": "warning",
        "courtyards_overlap": "error",
        "creepage": "error",
        "diff_pair_gap_out_of_range": "error",
        "diff_pair_uncoupled_length_too_long": "error",
        "drill_out_of_range": "error",
        "duplicate_footprints": "warning",
        "extra_footprint": "warning",
        "footprint": "error",
        "footprint_filters_mismatch": "ignore",
        "footprint_symbol_mismatch": "warning",
        "footprint_type_mismatch": "ignore",
        "hole_clearance": "error",
        "hole_to_hole": "error",
        "holes_co_located": "warning",
        "invalid_outline": "error",
        "isolated_copper": "warning",
        "item_on_disabled_layer": "error",
        "items_not_allowed": "error",
        "length_out_of_range": "error",
        "lib_footprint_issues": "warning",
        "lib_footprint_mismatch": "warning",
        "malformed_courtyard": "error",
        "microvia_drill_out_of_range": "error",
        "mirrored_text_on_front_layer": "warning",
        "missing_courtyard": "warning",
        "missing_footprint": "warning",
        "net_conflict": "warning",
        "nonmirrored_text_on_back_layer": "warning",
        "npth_inside_courtyard": "warning",
        "padstack": "error",
        "pth_inside_courtyard": "warning",
        "shorting_items": "error",
        "silk_edge_clearance": "warning",
        "silk_over_copper": "warning",
        "silk_overlap": "warning",
        "skew_out_of_range": "error",
        "solder_mask_bridge": "error",
        "starved_thermal": "error",
        "text_height": "warning",
        "text_on_edge_cuts": "error",
        "text_thickness": "warning",
        "through_hole_pad_without_hole": "error",
        "too_many_vias": "error",
        "track_angle": "error",
        "track_dangling": "warning",
        "track_segment_length": "error",
        "track_width": "error",
        "tracks_crossing": "error",
        "unconnected_items": "error",
        "unresolved_variable": "error",
        "via_dangling": "warning",
        "zones_intersect": "error"
      },
      "rules": {
        "max_error": 0.0025,
        "min_clearance": 0.125,
        "min_connection": 0.125,
        "min_copper_edge_clearance": 0.4,
        "min_groove_width": 0.0,
        "min_hole_clearance": 0.2,
        "min_hole_to_hole": 0.25,
        "min_microvia_diameter": 0.2,
        "min_microvia_drill": 0.1,
        "min_resolved_spokes": 1,
        "min_silk_clearance": 0.0,
        "min_text_height": 0.6,
        "min_text_thickness": 0.12,
        "min_through_hole_diameter": 0.1,
        "min_track_width": 0.125,
        "min_via_annular_width": 0.125,
        "min_via_diameter": 0.45,
        "solder_mask_to_copper_clearance": 0.0,
        "use_height_for_length_calcs": true
      },
      "teardrop_options": [
        {
          "td_onpthpad": true,
          "td_onroundshapesonly": false,
          "td_onsmdpad": true,
          "td_ontrackend": false,
          "td_onvia": true
        }
      ],
      "teardrop_parameters": [
        {
          "td_allow_use_two_tracks": true,
          "td_curve_segcount": 0,
          "td_height_ratio": 1.0,
          "td_length_ratio": 0.5,
          "td_maxheight": 2.0,
          "td_maxlen": 1.0,
          "td_on_pad_in_zone": false,
          "td_target_name": "td_round_shape",
          "td_width_to_size_filter_ratio": 0.9
        },
        {
          "td_allow_use_two_tracks": true,
          "td_curve_segcount": 0,
          "td_height_ratio": 1.0,
          "td_length_ratio": 0.5,
          "td_maxheight": 2.0,
          "td_maxlen": 1.0,
          "td_on_pad_in_zone": false,
          "td_target_name": "td_rect_shape",
          "td_width_to_size_filter_ratio": 0.9
        },
        {
          "td_allow_use_two_tracks": true,
          "td_curve_segcount": 0,
          "td_height_ratio": 1.0,
          "td_length_ratio": 0.5,
          "td_maxheight": 2.0,
          "td_maxlen": 1.0,
          "td_on_pad_in_zone": false,
          "td_target_name": "td_track_end",
          "td_width_to_size_filter_ratio": 0.9
        }
      ],
      "track_widths": [
        0.0,
        0.125,
        0.13,
        0.15,
        0.2,
        0.3,
        0.5,
        1.0
      ],
      "tuning_pattern_settings": {
        "diff_pair_defaults": {
          "corner_radius_percentage": 80,
          "corner_style": 1,
          "max_amplitude": 1.0,
          "min_amplitude": 0.2,
          "single_sided": false,
          "spacing": 1.0
        },
        "diff_pair_skew_defaults": {
          "corner_radius_percentage": 80,
          "corner_style": 1,
          "max_amplitude": 1.0,
          "min_amplitude": 0.2,
          "single_sided": false,
          "spacing": 0.6
        },
        "single_track_defaults": {
          "corner_radius_percentage": 80,
          "corner_style": 1,
          "max_amplitude": 1.0,
          "min_amplitude": 0.2,
          "single_sided": false,
          "spacing": 0.6
        }
      },
      "via_dimensions": [
        {
          "diameter": 0.0,
          "drill": 0.0
        },
        {
          "diameter": 0.45,
          "drill": 0.1
        }
      ],
      "zones_allow_external_fillets": true
    },
    "ipc2581": {
      "dist": "",
      "distpn": "",
      "internal_id": "",
      "mfg": "",
      "mpn": ""
    },
    "layer_pairs": [],
    "layer_presets": [],
    "viewports": []
  },
  "boards": [],
  "cvpcb": {
    "equivalence_files": []
  },
  "erc": {
    "erc_exclusions": [],
    "meta": {
      "version": 0
    },
    "pin_map": [
      [
        0,
        0,
        0,
        0,
        0,
        0,
        1,
        0,
        0,
        0,
        0,
        2
      ],
      [
        0,
        2,
        0,
        1,
        0,
        0,
        1,
        0,
        2,
        2,
        2,
        2
      ],
      [
        0,
        0,
        0,
        0,
        0,
        0,
        1,
        0,
        1,
        0,
        1,
        2
      ],
      [
        0,
        1,
        0,
        0,
        0,
        0,
        1,
        1,
        2,
        1,
        1,
        2
      ],
      [
        0,
        0,
        0,
        0,
        0,
        0,
        1,
        0,
        0,
        0,
        0,
        2
      ],
      [
        0,
        0,
        0,
        0,
        0,
        0,
        0,
        0,
        0,
        0,
        0,
        2
      ],
      [
        1,
        1,
        1,
        1,
        1,
        0,
        1,
        1,
        1,
        1,
        1,
        2
      ],
      [
        0,
        0,
        0,
        1,
        0,
        0,
        1,
        0,
        0,
        0,
        0,
        2
      ],
      [
        0,
        2,
        1,
        2,
        0,
        0,
        1,
        0,
        2,
        2,
        2,
        2
      ],
      [
        0,
        2,
        0,
        1,
        0,
        0,
        1,
        0,
        2,
        0,
        0,
        2
      ],
      [
        0,
        2,
        1,
        1,
        0,
        0,
        1,
        0,
        2,
        0,
        0,
        2
      ],
      [
        2,
        2,
        2,
        2,
        2,
        2,
        2,
        2,
        2,
        2,
        2,
        2
      ]
    ],
    "rule_severities": {
      "bus_definition_conflict": "error",
      "bus_entry_needed": "error",
      "bus_to_bus_conflict": "error",
      "bus_to_net_conflict": "error",
      "different_unit_footprint": "error",
      "different_unit_net": "error",
      "duplicate_reference": "error",
      "duplicate_sheet_names": "error",
      "endpoint_off_grid": "warning",
      "extra_units": "error",
      "footprint_filter": "ignore",
      "footprint_link_issues": "warning",
      "four_way_junction": "warning",
      "global_label_dangling": "warning",
      "hier_label_mismatch": "error",
      "label_dangling": "error",
      "label_multiple_wires": "warning",
      "lib_symbol_issues": "warning",
      "lib_symbol_mismatch": "warning",
      "missing_bidi_pin": "warning",
      "missing_input_pin": "warning",
      "missing_power_pin": "error",
      "missing_unit": "warning",
      "multiple_net_names": "warning",
      "net_not_bus_member": "warning",
      "no_connect_connected": "warning",
      "no_connect_dangling": "warning",
      "pin_not_connected": "error",
      "pin_not_driven": "error",
      "pin_to_pin": "warning",
      "power_pin_not_driven": "error",
      "same_local_global_label": "warning",
      "similar_label_and_power": "warning",
      "similar_labels": "warning",
      "similar_power": "warning",
      "simulation_model_issue": "ignore",
      "single_global_label": "warning",
      "unannotated": "error",
      "unconnected_wire_endpoint": "warning",
      "undefined_netclass": "error",
      "unit_value_mismatch": "error",
      "unresolved_variable": "error",
      "wire_dangling": "error"
    }
  },
  "libraries": {
    "pinned_footprint_libs": [],
    "pinned_symbol_libs": []
  },
  "meta": {
    "filename": "oculink-to-10gbe-adapter.kicad_pro",
    "version": 3
  },
  "net_settings": {
    "classes": [
      {
        "bus_width": 12,
        "clearance": 0.15,
        "diff_pair_gap": 0.25,
        "diff_pair_via_gap": 0.25,
        "diff_pair_width": 0.2,
        "line_style": 0,
        "microvia_diameter": 0.3,
        "microvia_drill": 0.1,
        "name": "Default",
        "pcb_color": "rgba(0, 0, 0, 0.000)",
        "priority": 2147483647,
        "schematic_color": "rgba(0, 0, 0, 0.000)",
        "track_width": 0.15,
        "via_diameter": 0.45,
        "via_drill": 0.1,
        "wire_width": 6
      },
      {
        "bus_width": 12,
        "clearance": 0.15,
        "diff_pair_gap": 0.22,
        "diff_pair_width": 0.16,
        "line_style": 0,
        "name": "100Ohm-diff_10GbE",
        "pcb_color": "rgb(0, 194, 194)",
        "priority": 3,
        "schematic_color": "rgb(0, 194, 194)",
        "track_width": 0.15,
        "via_diameter": 0.45,
        "via_drill": 0.1,
        "wire_width": 6
      },
      {
        "bus_width": 12,
        "clearance": 0.15,
        "diff_pair_gap": 0.22,
        "diff_pair_width": 0.16,
        "line_style": 0,
        "name": "100Ohm-diff_CLK",
        "pcb_color": "rgb(0, 194, 0)",
        "priority": 2,
        "schematic_color": "rgb(0, 194, 0)",
        "track_width": 0.15,
        "via_diameter": 0.45,
        "via_drill": 0.1,
        "wire_width": 6
      },
      {
        "bus_width": 12,
        "clearance": 0.15,
        "diff_pair_gap": 0.187,
        "diff_pair_width": 0.202,
        "line_style": 0,
        "name": "85Ohm-diff_PCIe",
        "pcb_color": "rgb(194, 0, 194)",
        "priority": 4,
        "schematic_color": "rgb(194, 0, 194)",
        "track_width": 0.15,
        "via_diameter": 0.45,
        "via_drill": 0.1,
        "wire_width": 6
      },
      {
        "bus_width": 12,
        "clearance": 0.15,
        "line_style": 0,
        "name": "GND",
        "pcb_color": "rgb(72, 72, 72)",
        "priority": 1,
        "schematic_color": "rgb(0, 0, 0)",
        "track_width": 0.15,
        "via_diameter": 0.45,
        "via_drill": 0.1,
        "wire_width": 6
      },
      {
        "bus_width": 12,
        "clearance": 0.15,
        "line_style": 0,
        "name": "PWR",
        "pcb_color": "rgb(255, 0, 0)",
        "priority": 0,
        "schematic_color": "rgb(255, 0, 0)",
        "track_width": 0.15,
        "via_diameter": 0.45,
        "via_drill": 0.1,
        "wire_width": 6
      }
    ],
    "meta": {
      "version": 4
    },
    "net_colors": null,
    "netclass_assignments": {
      "+1V88": [
        "PWR"
      ],
      "+3V3": [
        "PWR"
      ],
      "/2xRJ45/Ethernet_P0.D1+": [
        "100Ohm-diff_10GbE"
      ],
      "/2xRJ45/Ethernet_P0.D1-": [
        "100Ohm-diff_10GbE"
      ],
      "/2xRJ45/Ethernet_P0.D2+": [
        "100Ohm-diff_10GbE"
      ],
      "/2xRJ45/Ethernet_P0.D2-": [
        "100Ohm-diff_10GbE"
      ],
      "/2xRJ45/Ethernet_P0.D3+": [
        "100Ohm-diff_10GbE"
      ],
      "/2xRJ45/Ethernet_P0.D3-": [
        "100Ohm-diff_10GbE"
      ],
      "/2xRJ45/Ethernet_P0.D4+": [
        "100Ohm-diff_10GbE"
      ],
      "/2xRJ45/Ethernet_P0.D4-": [
        "100Ohm-diff_10GbE"
      ],
      "/2xRJ45/Ethernet_P0{10GbE}": [
        "100Ohm-diff_10GbE"
      ],
      "/2xRJ45/Ethernet_P1.D1+": [
        "100Ohm-diff_10GbE"
      ],
      "/2xRJ45/Ethernet_P1.D1-": [
        "100Ohm-diff_10GbE"
      ],
      "/2xRJ45/Ethernet_P1.D2+": [
        "100Ohm-diff_10GbE"
      ],
      "/2xRJ45/Ethernet_P1.D2-": [
        "100Ohm-diff_10GbE"
      ],
      "/2xRJ45/Ethernet_P1.D3+": [
        "100Ohm-diff_10GbE"
      ],
      "/2xRJ45/Ethernet_P1.D3-": [
        "100Ohm-diff_10GbE"
      ],
      "/2xRJ45/Ethernet_P1.D4+": [
        "100Ohm-diff_10GbE"
      ],
      "/2xRJ45/Ethernet_P1.D4-": [
        "100Ohm-diff_10GbE"
      ],
      "/2xRJ45/Ethernet_P1{10GbE}": [
        "100Ohm-diff_10GbE"
      ],
      "/Ethernet controller/Ethernet_P0.D1+": [
        "100Ohm-diff_10GbE"
      ],
      "/Ethernet controller/Ethernet_P0.D1-": [
        "100Ohm-diff_10GbE"
      ],
      "/Ethernet controller/Ethernet_P0.D2+": [
        "100Ohm-diff_10GbE"
      ],
      "/Ethernet controller/Ethernet_P0.D2-": [
        "100Ohm-diff_10GbE"
      ],
      "/Ethernet controller/Ethernet_P0.D3+": [
        "100Ohm-diff_10GbE"
      ],
      "/Ethernet controller/Ethernet_P0.D3-": [
        "100Ohm-diff_10GbE"
      ],
      "/Ethernet controller/Ethernet_P0.D4+": [
        "100Ohm-diff_10GbE"
      ],
      "/Ethernet controller/Ethernet_P0.D4-": [
        "100Ohm-diff_10GbE"
      ],
      "/Ethernet controller/Ethernet_P0{10GbE}": [
        "100Ohm-diff_10GbE"
      ],
      "/Ethernet controller/Ethernet_P1.D1+": [
        "100Ohm-diff_10GbE"
      ],
      "/Ethernet controller/Ethernet_P1.D1-": [
        "100Ohm-diff_10GbE"
      ],
      "/Ethernet controller/Ethernet_P1.D2+": [
        "100Ohm-diff_10GbE"
      ],
      "/Ethernet controller/Ethernet_P1.D2-": [
        "100Ohm-diff_10GbE"
      ],
      "/Ethernet controller/Ethernet_P1.D3+": [
        "100Ohm-diff_10GbE"
      ],
      "/Ethernet controller/Ethernet_P1.D3-": [
        "100Ohm-diff_10GbE"
      ],
      "/Ethernet controller/Ethernet_P1.D4+": [
        "100Ohm-diff_10GbE"
      ],
      "/Ethernet controller/Ethernet_P1.D4-": [
        "100Ohm-diff_10GbE"
      ],
      "/Ethernet controller/Ethernet_P1{10GbE}": [
        "100Ohm-diff_10GbE"
      ],
      "/Ethernet controller/P0_A_N": [
        "100Ohm-diff_10GbE"
      ],
      "/Ethernet controller/P0_A_P": [
        "100Ohm-diff_10GbE"
      ],
      "/Ethernet controller/P0_B_N": [
        "100Ohm-diff_10GbE"
      ],
      "/Ethernet controller/P0_B_P": [
        "100Ohm-diff_10GbE"
      ],
      "/Ethernet controller/P0_C_N": [
        "100Ohm-diff_10GbE"
      ],
      "/Ethernet controller/P0_C_P": [
        "100Ohm-diff_10GbE"
      ],
      "/Ethernet controller/P0_D_N": [
        "100Ohm-diff_10GbE"
      ],
      "/Ethernet controller/P0_D_P": [
        "100Ohm-diff_10GbE"
      ],
      "/Ethernet controller/P1_A_N": [
        "100Ohm-diff_10GbE"
      ],
      "/Ethernet controller/P1_A_P": [
        "100Ohm-diff_10GbE"
      ],
      "/Ethernet controller/P1_B_N": [
        "100Ohm-diff_10GbE"
      ],
      "/Ethernet controller/P1_B_P": [
        "100Ohm-diff_10GbE"
      ],
      "/Ethernet controller/P1_C_N": [
        "100Ohm-diff_10GbE"
      ],
      "/Ethernet controller/P1_C_P": [
        "100Ohm-diff_10GbE"
      ],
      "/Ethernet controller/P1_D_N": [
        "100Ohm-diff_10GbE"
      ],
      "/Ethernet controller/P1_D_P": [
        "100Ohm-diff_10GbE"
      ],
      "/Ethernet controller/PER_0_N": [
        "85Ohm-diff_PCIe"
      ],
      "/Ethernet controller/PER_0_P": [
        "85Ohm-diff_PCIe"
      ],
      "/Ethernet controller/PER_1_N": [
        "85Ohm-diff_PCIe"
      ],
      "/Ethernet controller/PER_1_P": [
        "85Ohm-diff_PCIe"
      ],
      "/Ethernet controller/PER_2_N": [
        "85Ohm-diff_PCIe"
      ],
      "/Ethernet controller/PER_2_P": [
        "85Ohm-diff_PCIe"
      ],
      "/Ethernet controller/PER_3_N": [
        "85Ohm-diff_PCIe"
      ],
      "/Ethernet controller/PER_3_P": [
        "85Ohm-diff_PCIe"
      ],
      "/Ethernet controller/PER_4_N": [
        "85Ohm-diff_PCIe"
      ],
      "/Ethernet controller/PER_4_P": [
        "85Ohm-diff_PCIe"
      ],
      "/Ethernet controller/PER_5_N": [
        "85Ohm-diff_PCIe"
      ],
      "/Ethernet controller/PER_5_P": [
        "85Ohm-diff_PCIe"
      ],
      "/Ethernet controller/PER_6_N": [
        "85Ohm-diff_PCIe"
      ],
      "/Ethernet controller/PER_6_P": [
        "85Ohm-diff_PCIe"
      ],
      "/Ethernet controller/PER_7_N": [
        "85Ohm-diff_PCIe"
      ],
      "/Ethernet controller/PER_7_P": [
        "85Ohm-diff_PCIe"
      ],
      "/Ethernet controller/PET_0_N": [
        "85Ohm-diff_PCIe"
      ],
      "/Ethernet controller/PET_0_P": [
        "85Ohm-diff_PCIe"
      ],
      "/Ethernet controller/PET_1_N": [
        "85Ohm-diff_PCIe"
      ],
      "/Ethernet controller/PET_1_P": [
        "85Ohm-diff_PCIe"
      ],
      "/Ethernet controller/PET_2_N": [
        "85Ohm-diff_PCIe"
      ],
      "/Ethernet controller/PET_2_P": [
        "85Ohm-diff_PCIe"
      ],
      "/Ethernet controller/PET_3_N": [
        "85Ohm-diff_PCIe"
      ],
      "/Ethernet controller/PET_3_P": [
        "85Ohm-diff_PCIe"
      ],
      "/Ethernet controller/PET_4_N": [
        "85Ohm-diff_PCIe"
      ],
      "/Ethernet controller/PET_4_P": [
        "85Ohm-diff_PCIe"
      ],
      "/Ethernet controller/PET_5_N": [
        "85Ohm-diff_PCIe"
      ],
      "/Ethernet controller/PET_5_P": [
        "85Ohm-diff_PCIe"
      ],
      "/Ethernet controller/PET_6_N": [
        "85Ohm-diff_PCIe"
      ],
      "/Ethernet controller/PET_6_P": [
        "85Ohm-diff_PCIe"
      ],
      "/Ethernet controller/PET_7_N": [
        "85Ohm-diff_PCIe"
      ],
      "/Ethernet controller/PET_7_P": [
        "85Ohm-diff_PCIe"
      ],
      "/Ethernet controller/PE_CLK_N": [
        "85Ohm-diff_PCIe"
      ],
      "/Ethernet controller/PE_CLK_P": [
        "85Ohm-diff_PCIe"
      ],
      "/OCuLink/PCIe_{x4}.RX0+": [
        "85Ohm-diff_PCIe"
      ],
      "/OCuLink/PCIe_{x4}.RX0-": [
        "85Ohm-diff_PCIe"
      ],
      "/OCuLink/PCIe_{x4}.RX1+": [
        "85Ohm-diff_PCIe"
      ],
      "/OCuLink/PCIe_{x4}.RX1-": [
        "85Ohm-diff_PCIe"
      ],
      "/OCuLink/PCIe_{x4}.RX2+": [
        "85Ohm-diff_PCIe"
      ],
      "/OCuLink/PCIe_{x4}.RX2-": [
        "85Ohm-diff_PCIe"
      ],
      "/OCuLink/PCIe_{x4}.RX3+": [
        "85Ohm-diff_PCIe"
      ],
      "/OCuLink/PCIe_{x4}.RX3-": [
        "85Ohm-diff_PCIe"
      ],
      "/OCuLink/PCIe_{x4}.RX4+": [
        "85Ohm-diff_PCIe"
      ],
      "/OCuLink/PCIe_{x4}.RX4-": [
        "85Ohm-diff_PCIe"
      ],
      "/OCuLink/PCIe_{x4}.RX5+": [
        "85Ohm-diff_PCIe"
      ],
      "/OCuLink/PCIe_{x4}.RX5-": [
        "85Ohm-diff_PCIe"
      ],
      "/OCuLink/PCIe_{x4}.RX6+": [
        "85Ohm-diff_PCIe"
      ],
      "/OCuLink/PCIe_{x4}.RX6-": [
        "85Ohm-diff_PCIe"
      ],
      "/OCuLink/PCIe_{x4}.RX7+": [
        "85Ohm-diff_PCIe"
      ],
      "/OCuLink/PCIe_{x4}.RX7-": [
        "85Ohm-diff_PCIe"
      ],
      "/OCuLink/PCIe_{x4}.TX0+": [
        "85Ohm-diff_PCIe"
      ],
      "/OCuLink/PCIe_{x4}.TX0-": [
        "85Ohm-diff_PCIe"
      ],
      "/OCuLink/PCIe_{x4}.TX1+": [
        "85Ohm-diff_PCIe"
      ],
      "/OCuLink/PCIe_{x4}.TX1-": [
        "85Ohm-diff_PCIe"
      ],
      "/OCuLink/PCIe_{x4}.TX2+": [
        "85Ohm-diff_PCIe"
      ],
      "/OCuLink/PCIe_{x4}.TX2-": [
        "85Ohm-diff_PCIe"
      ],
      "/OCuLink/PCIe_{x4}.TX3+": [
        "85Ohm-diff_PCIe"
      ],
      "/OCuLink/PCIe_{x4}.TX3-": [
        "85Ohm-diff_PCIe"
      ],
      "/OCuLink/PCIe_{x4}.TX4+": [
        "85Ohm-diff_PCIe"
      ],
      "/OCuLink/PCIe_{x4}.TX4-": [
        "85Ohm-diff_PCIe"
      ],
      "/OCuLink/PCIe_{x4}.TX5+": [
        "85Ohm-diff_PCIe"
      ],
      "/OCuLink/PCIe_{x4}.TX5-": [
        "85Ohm-diff_PCIe"
      ],
      "/OCuLink/PCIe_{x4}.TX6+": [
        "85Ohm-diff_PCIe"
      ],
      "/OCuLink/PCIe_{x4}.TX6-": [
        "85Ohm-diff_PCIe"
      ],
      "/OCuLink/PCIe_{x4}.TX7+": [
        "85Ohm-diff_PCIe"
      ],
      "/OCuLink/PCIe_{x4}.TX7-": [
        "85Ohm-diff_PCIe"
      ],
      "/OCuLink/PCIe_{x4}{PCIe}": [
        "85Ohm-diff_PCIe"
      ],
      "/OCuLink/REFCLK.+": [
        "85Ohm-diff_PCIe"
      ],
      "/OCuLink/REFCLK.-": [
        "85Ohm-diff_PCIe"
      ],
      "/OCuLink/REFCLK{CLK}": [
        "85Ohm-diff_PCIe"
      ],
      "/PCIe_{x4}_1.x4": [
        "85Ohm-diff_PCIe"
      ],
      "/Power/VCC": [
        "PWR"
      ],
      "/X710-AT PCIe/PCIE_{REF}.CK+": [
        "85Ohm-diff_PCIe"
      ],
      "/X710-AT PCIe/PCIE_{REF}.CK-": [
        "85Ohm-diff_PCIe"
      ],
      "/X710-AT PCIe/PCIe_{x4}.RX0+": [
        "85Ohm-diff_PCIe"
      ],
      "/X710-AT PCIe/PCIe_{x4}.RX0-": [
        "85Ohm-diff_PCIe"
      ],
      "/X710-AT PCIe/PCIe_{x4}.RX1+": [
        "85Ohm-diff_PCIe"
      ],
      "/X710-AT PCIe/PCIe_{x4}.RX1-": [
        "85Ohm-diff_PCIe"
      ],
      "/X710-AT PCIe/PCIe_{x4}.RX2+": [
        "85Ohm-diff_PCIe"
      ],
      "/X710-AT PCIe/PCIe_{x4}.RX2-": [
        "85Ohm-diff_PCIe"
      ],
      "/X710-AT PCIe/PCIe_{x4}.RX3+": [
        "85Ohm-diff_PCIe"
      ],
      "/X710-AT PCIe/PCIe_{x4}.RX3-": [
        "85Ohm-diff_PCIe"
      ],
      "/X710-AT PCIe/PCIe_{x4}.RX4+": [
        "85Ohm-diff_PCIe"
      ],
      "/X710-AT PCIe/PCIe_{x4}.RX4-": [
        "85Ohm-diff_PCIe"
      ],
      "/X710-AT PCIe/PCIe_{x4}.RX5+": [
        "85Ohm-diff_PCIe"
      ],
      "/X710-AT PCIe/PCIe_{x4}.RX5-": [
        "85Ohm-diff_PCIe"
      ],
      "/X710-AT PCIe/PCIe_{x4}.RX6+": [
        "85Ohm-diff_PCIe"
      ],
      "/X710-AT PCIe/PCIe_{x4}.RX6-": [
        "85Ohm-diff_PCIe"
      ],
      "/X710-AT PCIe/PCIe_{x4}.RX7+": [
        "85Ohm-diff_PCIe"
      ],
      "/X710-AT PCIe/PCIe_{x4}.RX7-": [
        "85Ohm-diff_PCIe"
      ],
      "/X710-AT PCIe/PCIe_{x4}.TX0+": [
        "85Ohm-diff_PCIe"
      ],
      "/X710-AT PCIe/PCIe_{x4}.TX0-": [
        "85Ohm-diff_PCIe"
      ],
      "/X710-AT PCIe/PCIe_{x4}.TX1+": [
        "85Ohm-diff_PCIe"
      ],
      "/X710-AT PCIe/PCIe_{x4}.TX1-": [
        "85Ohm-diff_PCIe"
      ],
      "/X710-AT PCIe/PCIe_{x4}.TX2+": [
        "85Ohm-diff_PCIe"
      ],
      "/X710-AT PCIe/PCIe_{x4}.TX2-": [
        "85Ohm-diff_PCIe"
      ],
      "/X710-AT PCIe/PCIe_{x4}.TX3+": [
        "85Ohm-diff_PCIe"
      ],
      "/X710-AT PCIe/PCIe_{x4}.TX3-": [
        "85Ohm-diff_PCIe"
      ],
      "/X710-AT PCIe/PCIe_{x4}.TX4+": [
        "85Ohm-diff_PCIe"
      ],
      "/X710-AT PCIe/PCIe_{x4}.TX4-": [
        "85Ohm-diff_PCIe"
      ],
      "/X710-AT PCIe/PCIe_{x4}.TX5+": [
        "85Ohm-diff_PCIe"
      ],
      "/X710-AT PCIe/PCIe_{x4}.TX5-": [
        "85Ohm-diff_PCIe"
      ],
      "/X710-AT PCIe/PCIe_{x4}.TX6+": [
        "85Ohm-diff_PCIe"
      ],
      "/X710-AT PCIe/PCIe_{x4}.TX6-": [
        "85Ohm-diff_PCIe"
      ],
      "/X710-AT PCIe/PCIe_{x4}.TX7+": [
        "85Ohm-diff_PCIe"
      ],
      "/X710-AT PCIe/PCIe_{x4}.TX7-": [
        "85Ohm-diff_PCIe"
      ],
      "/X710-AT PCIe/PCIe_{x4}{PCIe}": [
        "85Ohm-diff_PCIe"
      ],
      "/X710-AT2 10GbE/25MHZ_OSC.+": [
        "100Ohm-diff_CLK"
      ],
      "/X710-AT2 10GbE/25MHZ_OSC.-": [
        "100Ohm-diff_CLK"
      ],
      "/X710-AT2 10GbE/25MHZ_OSC_AC.+": [
        "100Ohm-diff_CLK"
      ],
      "/X710-AT2 10GbE/25MHZ_OSC_AC.-": [
        "100Ohm-diff_CLK"
      ],
      "/X710-AT2 10GbE/25MHZ_OSC_R.+": [
        "100Ohm-diff_CLK"
      ],
      "/X710-AT2 10GbE/25MHZ_OSC_R.-": [
        "100Ohm-diff_CLK"
      ],
      "/X710-AT2 10GbE/Ethernet_P0.10GbE": [
        "100Ohm-diff_10GbE"
      ],
      "/X710-AT2 10GbE/Ethernet_P0.D1+": [
        "100Ohm-diff_10GbE"
      ],
      "/X710-AT2 10GbE/Ethernet_P0.D1-": [
        "100Ohm-diff_10GbE"
      ],
      "/X710-AT2 10GbE/Ethernet_P0.D2+": [
        "100Ohm-diff_10GbE"
      ],
      "/X710-AT2 10GbE/Ethernet_P0.D2-": [
        "100Ohm-diff_10GbE"
      ],
      "/X710-AT2 10GbE/Ethernet_P0.D3+": [
        "100Ohm-diff_10GbE"
      ],
      "/X710-AT2 10GbE/Ethernet_P0.D3-": [
        "100Ohm-diff_10GbE"
      ],
      "/X710-AT2 10GbE/Ethernet_P0.D4+": [
        "100Ohm-diff_10GbE"
      ],
      "/X710-AT2 10GbE/Ethernet_P0.D4-": [
        "100Ohm-diff_10GbE"
      ],
      "/X710-AT2 10GbE/Ethernet_P0{10GbE}": [
        "100Ohm-diff_10GbE"
      ],
      "/X710-AT2 10GbE/Ethernet_P1.10GbE": [
        "100Ohm-diff_10GbE"
      ],
      "/X710-AT2 10GbE/Ethernet_P1.D1+": [
        "100Ohm-diff_10GbE"
      ],
      "/X710-AT2 10GbE/Ethernet_P1.D1-": [
        "100Ohm-diff_10GbE"
      ],
      "/X710-AT2 10GbE/Ethernet_P1.D2+": [
        "100Ohm-diff_10GbE"
      ],
      "/X710-AT2 10GbE/Ethernet_P1.D2-": [
        "100Ohm-diff_10GbE"
      ],
      "/X710-AT2 10GbE/Ethernet_P1.D3+": [
        "100Ohm-diff_10GbE"
      ],
      "/X710-AT2 10GbE/Ethernet_P1.D3-": [
        "100Ohm-diff_10GbE"
      ],
      "/X710-AT2 10GbE/Ethernet_P1.D4+": [
        "100Ohm-diff_10GbE"
      ],
      "/X710-AT2 10GbE/Ethernet_P1.D4-": [
        "100Ohm-diff_10GbE"
      ],
      "/X710-AT2 10GbE/Ethernet_P1{10GbE}": [
        "100Ohm-diff_10GbE"
      ],
      "/X710-AT2 PCIe/CLK+": [
        "85Ohm-diff_PCIe"
      ],
      "/X710-AT2 PCIe/CLK-": [
        "85Ohm-diff_PCIe"
      ],
      "/X710-AT2 PCIe/GEN_CLK+": [
        "85Ohm-diff_PCIe"
      ],
      "/X710-AT2 PCIe/GEN_CLK-": [
        "85Ohm-diff_PCIe"
      ],
      "/X710-AT2 PCIe/GEN_F_CLK+": [
        "85Ohm-diff_PCIe"
      ],
      "/X710-AT2 PCIe/GEN_F_CLK-": [
        "85Ohm-diff_PCIe"
      ],
      "/X710-AT2 PCIe/PCIE_{REF}.CK+": [
        "85Ohm-diff_PCIe"
      ],
      "/X710-AT2 PCIe/PCIE_{REF}.CK-": [
        "85Ohm-diff_PCIe"
      ],
      "/X710-AT2 PCIe/PCIe_{x4}.PCIe": [
        "85Ohm-diff_PCIe"
      ],
      "/X710-AT2 PCIe/PCIe_{x4}.RX0+": [
        "85Ohm-diff_PCIe"
      ],
      "/X710-AT2 PCIe/PCIe_{x4}.RX0-": [
        "85Ohm-diff_PCIe"
      ],
      "/X710-AT2 PCIe/PCIe_{x4}.RX1+": [
        "85Ohm-diff_PCIe"
      ],
      "/X710-AT2 PCIe/PCIe_{x4}.RX1-": [
        "85Ohm-diff_PCIe"
      ],
      "/X710-AT2 PCIe/PCIe_{x4}.RX2+": [
        "85Ohm-diff_PCIe"
      ],
      "/X710-AT2 PCIe/PCIe_{x4}.RX2-": [
        "85Ohm-diff_PCIe"
      ],
      "/X710-AT2 PCIe/PCIe_{x4}.RX3+": [
        "85Ohm-diff_PCIe"
      ],
      "/X710-AT2 PCIe/PCIe_{x4}.RX3-": [
        "85Ohm-diff_PCIe"
      ],
      "/X710-AT2 PCIe/PCIe_{x4}.RX4+": [
        "85Ohm-diff_PCIe"
      ],
      "/X710-AT2 PCIe/PCIe_{x4}.RX4-": [
        "85Ohm-diff_PCIe"
      ],
      "/X710-AT2 PCIe/PCIe_{x4}.RX5+": [
        "85Ohm-diff_PCIe"
      ],
      "/X710-AT2 PCIe/PCIe_{x4}.RX5-": [
        "85Ohm-diff_PCIe"
      ],
      "/X710-AT2 PCIe/PCIe_{x4}.RX6+": [
        "85Ohm-diff_PCIe"
      ],
      "/X710-AT2 PCIe/PCIe_{x4}.RX6-": [
        "85Ohm-diff_PCIe"
      ],
      "/X710-AT2 PCIe/PCIe_{x4}.RX7+": [
        "85Ohm-diff_PCIe"
      ],
      "/X710-AT2 PCIe/PCIe_{x4}.RX7-": [
        "85Ohm-diff_PCIe"
      ],
      "/X710-AT2 PCIe/PCIe_{x4}.TX0+": [
        "85Ohm-diff_PCIe"
      ],
      "/X710-AT2 PCIe/PCIe_{x4}.TX0-": [
        "85Ohm-diff_PCIe"
      ],
      "/X710-AT2 PCIe/PCIe_{x4}.TX1+": [
        "85Ohm-diff_PCIe"
      ],
      "/X710-AT2 PCIe/PCIe_{x4}.TX1-": [
        "85Ohm-diff_PCIe"
      ],
      "/X710-AT2 PCIe/PCIe_{x4}.TX2+": [
        "85Ohm-diff_PCIe"
      ],
      "/X710-AT2 PCIe/PCIe_{x4}.TX2-": [
        "85Ohm-diff_PCIe"
      ],
      "/X710-AT2 PCIe/PCIe_{x4}.TX3+": [
        "85Ohm-diff_PCIe"
      ],
      "/X710-AT2 PCIe/PCIe_{x4}.TX3-": [
        "85Ohm-diff_PCIe"
      ],
      "/X710-AT2 PCIe/PCIe_{x4}.TX4+": [
        "85Ohm-diff_PCIe"
      ],
      "/X710-AT2 PCIe/PCIe_{x4}.TX4-": [
        "85Ohm-diff_PCIe"
      ],
      "/X710-AT2 PCIe/PCIe_{x4}.TX5+": [
        "85Ohm-diff_PCIe"
      ],
      "/X710-AT2 PCIe/PCIe_{x4}.TX5-": [
        "85Ohm-diff_PCIe"
      ],
      "/X710-AT2 PCIe/PCIe_{x4}.TX6+": [
        "85Ohm-diff_PCIe"
      ],
      "/X710-AT2 PCIe/PCIe_{x4}.TX6-": [
        "85Ohm-diff_PCIe"
      ],
      "/X710-AT2 PCIe/PCIe_{x4}.TX7+": [
        "85Ohm-diff_PCIe"
      ],
      "/X710-AT2 PCIe/PCIe_{x4}.TX7-": [
        "85Ohm-diff_PCIe"
      ],
      "/X710-AT2 PCIe/PCIe_{x4}_AC.TX0+": [
        "85Ohm-diff_PCIe"
      ],
      "/X710-AT2 PCIe/PCIe_{x4}_AC.TX0-": [
        "85Ohm-diff_PCIe"
      ],
      "/X710-AT2 PCIe/PCIe_{x4}_AC.TX1+": [
        "85Ohm-diff_PCIe"
      ],
      "/X710-AT2 PCIe/PCIe_{x4}_AC.TX1-": [
        "85Ohm-diff_PCIe"
      ],
      "/X710-AT2 PCIe/PCIe_{x4}_AC.TX2+": [
        "85Ohm-diff_PCIe"
      ],
      "/X710-AT2 PCIe/PCIe_{x4}_AC.TX2-": [
        "85Ohm-diff_PCIe"
      ],
      "/X710-AT2 PCIe/PCIe_{x4}_AC.TX3+": [
        "85Ohm-diff_PCIe"
      ],
      "/X710-AT2 PCIe/PCIe_{x4}_AC.TX3-": [
        "85Ohm-diff_PCIe"
      ],
      "/X710-AT2 PCIe/PCIe_{x4}{PCIe}": [
        "85Ohm-diff_PCIe"
      ],
      "/X710-AT2 PCIe/REFCLK.+": [
        "85Ohm-diff_PCIe"
      ],
      "/X710-AT2 PCIe/REFCLK.-": [
        "85Ohm-diff_PCIe"
      ],
      "1P88V": [
        "PWR"
      ],
      "3P3V": [
        "PWR"
      ],
      "AVDDH": [
        "PWR"
      ],
      "DVDD": [
        "PWR"
      ],
      "Net-(U1A-PET_0_N)": [
        "85Ohm-diff_PCIe"
      ],
      "Net-(U1A-PET_0_P)": [
        "85Ohm-diff_PCIe"
      ],
      "Net-(U1A-PET_1_N)": [
        "85Ohm-diff_PCIe"
      ],
      "Net-(U1A-PET_1_P)": [
        "85Ohm-diff_PCIe"
      ],
      "Net-(U1A-PET_2_N)": [
        "85Ohm-diff_PCIe"
      ],
      "Net-(U1A-PET_2_P)": [
        "85Ohm-diff_PCIe"
      ],
      "Net-(U1A-PET_3_N)": [
        "85Ohm-diff_PCIe"
      ],
      "Net-(U1A-PET_3_P)": [
        "85Ohm-diff_PCIe"
      ],
      "P0_AVDDL": [
        "PWR"
      ],
      "P1_AVDDL": [
        "PWR"
      ],
      "PLL_VDD": [
        "PWR"
      ],
      "VCC": [
        "PWR"
      ],
      "VCCA": [
        "PWR"
      ],
      "VCCD": [
        "PWR"
      ],
      "XFI_PVDD": [
        "PWR"
      ],
      "XFI_VDD": [
        "PWR"
      ],
      "XGB_AVDDH": [
        "PWR"
      ]
    },
    "netclass_patterns": [
      {
        "netclass": "GND",
        "pattern": "GND"
      },
      {
        "netclass": "PWR",
        "pattern": "*+*V*"
      }
    ]
  },
  "pcbnew": {
    "last_paths": {
      "gencad": "",
      "idf": "",
      "netlist": "",
      "plot": "",
      "pos_files": "",
      "specctra_dsn": "",
      "step": "",
      "svg": "",
      "vrml": ""
    },
    "page_layout_descr_file": ""
  },
  "schematic": {
    "annotate_start_num": 0,
    "bom_export_filename": "${PROJECTNAME}.csv",
    "bom_fmt_presets": [],
    "bom_fmt_settings": {
      "field_delimiter": ",",
      "keep_line_breaks": false,
      "keep_tabs": false,
      "name": "CSV",
      "ref_delimiter": ",",
      "ref_range_delimiter": "",
      "string_delimiter": "\""
    },
    "bom_presets": [],
    "bom_settings": {
      "exclude_dnp": false,
      "fields_ordered": [
        {
          "group_by": false,
          "label": "Reference",
          "name": "Reference",
          "show": true
        },
        {
          "group_by": false,
          "label": "Qty",
          "name": "${QUANTITY}",
          "show": true
        },
        {
          "group_by": true,
          "label": "Value",
          "name": "Value",
          "show": true
        },
        {
          "group_by": true,
          "label": "DNP",
          "name": "${DNP}",
          "show": true
        },
        {
          "group_by": true,
          "label": "Exclude from BOM",
          "name": "${EXCLUDE_FROM_BOM}",
          "show": true
        },
        {
          "group_by": true,
          "label": "Exclude from Board",
          "name": "${EXCLUDE_FROM_BOARD}",
          "show": true
        },
        {
          "group_by": true,
          "label": "Footprint",
          "name": "Footprint",
          "show": true
        },
        {
          "group_by": false,
          "label": "Datasheet",
          "name": "Datasheet",
          "show": true
        }
      ],
      "filter_string": "",
      "group_symbols": true,
      "include_excluded_from_bom": true,
      "name": "Default Editing",
      "sort_asc": true,
      "sort_field": "Reference"
    },
    "connection_grid_size": 50.0,
    "drawing": {
      "dashed_lines_dash_length_ratio": 12.0,
      "dashed_lines_gap_length_ratio": 3.0,
      "default_line_thickness": 6.0,
      "default_text_size": 50.0,
      "field_names": [],
      "intersheets_ref_own_page": false,
      "intersheets_ref_prefix": "",
      "intersheets_ref_short": false,
      "intersheets_ref_show": false,
      "intersheets_ref_suffix": "",
      "junction_size_choice": 3,
      "label_size_ratio": 0.375,
      "operating_point_overlay_i_precision": 3,
      "operating_point_overlay_i_range": "~A",
      "operating_point_overlay_v_precision": 3,
      "operating_point_overlay_v_range": "~V",
      "overbar_offset_ratio": 1.23,
      "pin_symbol_size": 25.0,
      "text_offset_ratio": 0.15
    },
    "legacy_lib_dir": "",
    "legacy_lib_list": [],
    "meta": {
      "version": 1
    },
    "net_format_name": "",
    "page_layout_descr_file": "",
    "plot_directory": "",
    "space_save_all_events": true,
    "spice_current_sheet_as_root": false,
    "spice_external_command": "spice \"%I\"",
    "spice_model_current_sheet_as_root": true,
    "spice_save_all_currents": false,
    "spice_save_all_dissipations": false,
    "spice_save_all_voltages": false,
    "subpart_first_id": 65,
    "subpart_id_separator": 0
  },
  "sheets": [
    [
      "",
      "Root"
    ],
    [
      "",
      "Power"
    ],
    [
      "",
      "Flash memory"
    ],
    [
      "",
      "2xRJ45"
    ],
    [
      "",
      "X710-AT2 power"
    ],
    [
      "",
      "X710-AT2 PCIe"
    ],
    [
      "",
      "X710-AT2 10GbE"
    ],
    [
      "",
      "X710-AT2 Misc"
    ],
    [
      "",
      "X710-AT2 RSVD"
    ],
    [
      "",
      "OCuLink"
    ],
    [
      "",
      "Ideal diode 1"
    ],
    [
      "",
      "Ideal diode 2"
    ],
    [
      "",
      "Fan controller"
    ]
  ],
  "text_variables": {}
}
